# S9S_MB_2U (Grand Teton) — schematic netlist excerpt (pin names and nets, part order shuffled) for the footprints in the layout excerpt that follows; sources: Cadence DE-HDL packaged netlist, KiCad conversion of 03242023_DA0F0TMBIJ0_F0T_Motherboard_J_brd_V01_OCP.brd

C728  Q_CAP_DIFFBUS  DIFF BUS_0.22UF 6.3V 20% X6S  pkg C0201  page 176 : \1\ = P5E_CPU1_PE0_TX_C_DN<6> ; \2\ = P5E_CPU1_PE0_TX_DN<6>

PPQ7  MOSFET_NCH_1D3S  PSMNR58-30YLH EMPTY  pkg SOT1023  page 304
  \1\  = P12V_AUX
  \2\  = P12V_AUX
  \3\  = P12V_AUX
  \4\  = P12V_HSC_GATE_G3
  \5\  = P12V_MAIN_R

(kicad_pcb
	(version 20260206)
	(generator "pcbnew")
	(generator_version "10.0")
	(general
		(thickness 1.6)
		(legacy_teardrops no)
	)
	(paper "A4")
	(title_block
		(title "03242023_DA0F0TMBIJ0_F0T_Motherboard_J_brd_V01_OCP.brd")
		(comment 1 "Grand Teton / footprints 3305-3306 of 6105")
	)
	(layers
		(0 "F.Cu" signal "TOP")
		(4 "In1.Cu" signal "GND")
		(6 "In2.Cu" signal "IN1")
		(8 "In3.Cu" signal "GND1")
		(10 "In4.Cu" signal "IN2")
		(12 "In5.Cu" signal "GND2")
		(14 "In6.Cu" signal "IN3")
		(16 "In7.Cu" signal "GND3")
		(18 "In8.Cu" signal "VCC")
		(20 "In9.Cu" signal "VCC1")
		(22 "In10.Cu" signal "GND4")
		(24 "In11.Cu" signal "IN4")
		(26 "In12.Cu" signal "GND5")
		(28 "In13.Cu" signal "IN5")
		(30 "In14.Cu" signal "GND6")
		(32 "In15.Cu" signal "IN6")
		(34 "In16.Cu" signal "GND7")
		(2 "B.Cu" signal "BOTTOM")
		(9 "F.Adhes" user "F.Adhesive")
		(11 "B.Adhes" user "B.Adhesive")
		(13 "F.Paste" user "Package Geometry/Pastemask Top")
		(15 "B.Paste" user "Package Geometry/Pastemask Bottom")
		(5 "F.SilkS" user "Ref Des/Silkscreen Top")
		(7 "B.SilkS" user "Ref Des/Silkscreen Bottom")
		(1 "F.Mask" user "Board Geometry/Soldermask Top")
		(3 "B.Mask" user "Board Geometry/Soldermask Bottom")
		(17 "Dwgs.User" user "User.Drawings")
		(19 "Cmts.User" user "User.Comments")
		(21 "Eco1.User" user "User.Eco1")
		(23 "Eco2.User" user "User.Eco2")
		(25 "Edge.Cuts" user "Board Geometry/Outline")
		(27 "Margin" user)
		(31 "F.CrtYd" user "Package Geometry/Place Bound Top")
		(29 "B.CrtYd" user "Package Geometry/Place Bound Bottom")
		(35 "F.Fab" user "Ref Des/Assembly Top")
		(33 "B.Fab" user "Ref Des/Assembly Bottom")
	)
	(footprint ""
		(layer "F.Cu")
		(at 266.031472 -398.78 90)
		(property "Reference" "PPQ7"
			(at -8.177784 -1.879092 0)
			(unlocked yes)
			(layer "F.SilkS")
			(effects
				(font
					(size 0.7874 0.5842)
					(thickness 0.1524)
				)
				(justify left)
			)
		)
		(property "Value" ""
			(at 0 0 90)
			(layer "F.Fab")
			(effects
				(font
					(size 1.27 1.27)
				)
			)
		)
		(duplicate_pad_numbers_are_jumpers no)
		(fp_line
			(start 2.350008 -2.649982)
			(end 2.350008 -2.4892)
			(stroke
				(width 0.1524)
				(type default)
			)
			(layer "F.SilkS")
		)
		(fp_line
			(start -2.350008 -2.649982)
			(end 2.350008 -2.649982)
			(stroke
				(width 0.1524)
				(type default)
			)
			(layer "F.SilkS")
		)
		(fp_line
			(start -2.350008 -2.4384)
			(end -2.350008 -2.649982)
			(stroke
				(width 0.1524)
				(type default)
			)
			(layer "F.SilkS")
		)
		(fp_line
			(start 2.350008 2.4892)
			(end 2.350008 2.649982)
			(stroke
				(width 0.1524)
				(type default)
			)
			(layer "F.SilkS")
		)
		(fp_line
			(start 2.350008 2.649982)
			(end -2.350008 2.649982)
			(stroke
				(width 0.1524)
				(type default)
			)
			(layer "F.SilkS")
		)
		(fp_line
			(start -2.350008 2.649982)
			(end -2.350008 2.413)
			(stroke
				(width 0.1524)
				(type default)
			)
			(layer "F.SilkS")
		)
		(fp_poly
			(pts
				(xy -3.717544 -1.905) (xy -4.758944 -2.3241) (xy -4.758944 -1.524)
			)
			(stroke
				(width 0)
				(type default)
			)
			(fill yes)
			(layer "F.SilkS")
		)
		(fp_line
			(start 2.350008 -2.649982)
			(end 2.350008 2.649982)
			(stroke
				(width 0.1)
				(type default)
			)
			(layer "F.Fab")
		)
		(fp_line
			(start -2.350008 -2.649982)
			(end 2.350008 -2.649982)
			(stroke
				(width 0.1)
				(type default)
			)
			(layer "F.Fab")
		)
		(fp_line
			(start 2.350008 2.649982)
			(end -2.350008 2.649982)
			(stroke
				(width 0.1)
				(type default)
			)
			(layer "F.Fab")
		)
		(fp_line
			(start -2.350008 2.649982)
			(end -2.350008 -2.649982)
			(stroke
				(width 0.1)
				(type default)
			)
			(layer "F.Fab")
		)
		(fp_poly
			(pts
				(xy -3.717544 -1.905) (xy -4.758944 -2.3241) (xy -4.758944 -1.524)
			)
			(stroke
				(width 0)
				(type default)
			)
			(fill yes)
			(layer "F.Fab")
		)
		(pad "1" smd rect
			(at -2.999994 -1.905)
			(size 0.7112 1.1684)
			(layers "F.Cu" "F.Mask" "F.Paste")
			(net "P12V_AUX")
		)
		(pad "2" smd rect
			(at -2.999994 -0.635)
			(size 0.7112 1.1684)
			(layers "F.Cu" "F.Mask" "F.Paste")
			(net "P12V_AUX")
		)
		(pad "3" smd rect
			(at -2.999994 0.635)
			(size 0.7112 1.1684)
			(layers "F.Cu" "F.Mask" "F.Paste")
			(net "P12V_AUX")
		)
		(pad "4" smd rect
			(at -2.999994 1.905)
			(size 0.7112 1.1684)
			(layers "F.Cu" "F.Mask" "F.Paste")
			(net "P12V_HSC_GATE_G3")
		)
		(pad "5" smd circle
			(at 0.925068 0)
			(size 0 0)
			(layers "F.Cu" "F.Mask" "F.Paste")
			(net "P12V_MAIN_R")
		)
		(zone
			(layer "F.Cu")
			(hatch none 0.5)
			(connect_pads
				(clearance 0)
			)
			(min_thickness 0.25)
			(keepout
				(tracks not_allowed)
				(vias allowed)
				(pads allowed)
				(copperpour not_allowed)
				(footprints allowed)
			)
			(placement
				(enabled no)
				(sheetname "")
			)
			(fill
				(thermal_gap 0.5)
				(thermal_bridge_width 0.5)
				(island_removal_mode 0)
			)
			(polygon
				(pts
					(xy 263.872472 -397.3322) (xy 268.190472 -397.3322) (xy 268.673072 -397.3322) (xy 268.673072 -396.4305)
					(xy 263.389872 -396.4305) (xy 263.389872 -397.3322)
				)
			)
		)
	)
	(footprint ""
		(layer "F.Cu")
		(at 75.523598 -402.371052 -90)
		(property "Reference" "C728"
			(at 0 0 270)
			(layer "F.SilkS")
			(hide yes)
			(effects
				(font
					(size 1.27 1.27)
				)
			)
		)
		(property "Value" ""
			(at 0 0 270)
			(layer "F.Fab")
			(effects
				(font
					(size 1.27 1.27)
				)
			)
		)
		(duplicate_pad_numbers_are_jumpers no)
		(fp_line
			(start -0.299974 0.150114)
			(end -0.299974 -0.150114)
			(stroke
				(width 0.1)
				(type default)
			)
			(layer "F.Fab")
		)
		(fp_line
			(start 0.299974 0.150114)
			(end -0.299974 0.150114)
			(stroke
				(width 0.1)
				(type default)
			)
			(layer "F.Fab")
		)
		(fp_line
			(start -0.299974 -0.150114)
			(end 0.299974 -0.150114)
			(stroke
				(width 0.1)
				(type default)
			)
			(layer "F.Fab")
		)
		(fp_line
			(start 0.299974 -0.150114)
			(end 0.299974 0.150114)
			(stroke
				(width 0.1)
				(type default)
			)
			(layer "F.Fab")
		)
		(pad "1" smd rect
			(at -0.2667 0 270)
			(size 0.3048 0.381)
			(layers "F.Cu" "F.Mask" "F.Paste")
			(net "P5E_CPU1_PE0_TX_C_DN<6>")
		)
		(pad "2" smd rect
			(at 0.2667 0 270)
			(size 0.3048 0.381)
			(layers "F.Cu" "F.Mask" "F.Paste")
			(net "P5E_CPU1_PE0_TX_DN<6>")
		)
	)
)
